(kicad_pcb
	(version 20260206)
	(generator "pcbnew")
	(generator_version "10.0")
	(general
		(thickness 1.6)
		(legacy_teardrops no)
	)
	(paper "A4")
	(title_block
		(title "Bryce Canyon_IOM_IOC_16318-2_OCP.brd")
		(comment 1 "Bryce Canyon / footprints 83-89 of 1605")
	)
	(layers
		(0 "F.Cu" signal "TOP")
		(4 "In1.Cu" signal "L2GND")
		(6 "In2.Cu" signal "L3")
		(8 "In3.Cu" signal "L4VCC")
		(10 "In4.Cu" signal "L5VCC")
		(12 "In5.Cu" signal "L6")
		(14 "In6.Cu" signal "L7GND")
		(2 "B.Cu" signal "BOTTOM")
		(9 "F.Adhes" user "F.Adhesive")
		(11 "B.Adhes" user "B.Adhesive")
		(13 "F.Paste" user "Package Geometry/Pastemask Top")
		(15 "B.Paste" user "Package Geometry/Pastemask Bottom")
		(5 "F.SilkS" user "Ref Des/Silkscreen Top")
		(7 "B.SilkS" user "Ref Des/Silkscreen Bottom")
		(1 "F.Mask" user "Board Geometry/Soldermask Top")
		(3 "B.Mask" user "Board Geometry/Soldermask Bottom")
		(17 "Dwgs.User" user "User.Drawings")
		(19 "Cmts.User" user "User.Comments")
		(21 "Eco1.User" user "User.Eco1")
		(23 "Eco2.User" user "User.Eco2")
		(25 "Edge.Cuts" user "Board Geometry/Outline")
		(27 "Margin" user)
		(31 "F.CrtYd" user "Package Geometry/Place Bound Top")
		(29 "B.CrtYd" user "Package Geometry/Place Bound Bottom")
		(35 "F.Fab" user "Ref Des/Assembly Top")
		(33 "B.Fab" user "Ref Des/Assembly Bottom")
	)
	(footprint ""
		(layer "F.Cu")
		(at 190.4238 -105.791)
		(property "Reference" "C265"
			(at 0 0 0)
			(layer "F.SilkS")
			(hide yes)
			(effects
				(font
					(size 1.27 1.27)
				)
			)
		)
		(property "Value" "SC22U6D3V6KX-2-GP"
			(at -0.0762 -5.1308 0)
			(unlocked yes)
			(layer "F.Fab")
			(hide yes)
			(effects
				(font
					(size 1.016 1.016)
					(thickness 0.1524)
				)
			)
		)
		(property "Device Type" "C1206H71"
			(at -0.127 -6.6548 0)
			(unlocked yes)
			(layer "F.Fab")
			(hide yes)
			(effects
				(font
					(size 1.016 1.016)
					(thickness 0.1524)
				)
			)
		)
		(duplicate_pad_numbers_are_jumpers no)
		(fp_line
			(start -1.016 -2.2352)
			(end 1.016 -2.2352)
			(stroke
				(width 0.1524)
				(type default)
			)
			(layer "F.SilkS")
		)
		(fp_line
			(start -1.016 -0.8382)
			(end -1.016 -2.2352)
			(stroke
				(width 0.1524)
				(type default)
			)
			(layer "F.SilkS")
		)
		(fp_line
			(start -1.016 2.2352)
			(end -1.016 0.8382)
			(stroke
				(width 0.1524)
				(type default)
			)
			(layer "F.SilkS")
		)
		(fp_line
			(start 1.016 -2.2352)
			(end 1.016 -0.8382)
			(stroke
				(width 0.1524)
				(type default)
			)
			(layer "F.SilkS")
		)
		(fp_line
			(start 1.016 0.8382)
			(end 1.016 2.2352)
			(stroke
				(width 0.1524)
				(type default)
			)
			(layer "F.SilkS")
		)
		(fp_line
			(start 1.016 2.2352)
			(end -1.016 2.2352)
			(stroke
				(width 0.1524)
				(type default)
			)
			(layer "F.SilkS")
		)
		(fp_rect
			(start -1.0922 2.3114)
			(end 1.0922 -2.3114)
			(stroke
				(width 0)
				(type default)
			)
			(fill no)
			(layer "F.CrtYd")
		)
		(fp_poly
			(pts
				(xy 1.0922 -2.3114) (xy 1.0922 2.3114) (xy -1.0922 2.3114) (xy -1.0922 -2.3114)
			)
			(stroke
				(width 0)
				(type default)
			)
			(fill no)
			(layer "F.Fab")
		)
		(pad "1" smd rect
			(at 0 -1.397)
			(size 1.651 1.27)
			(layers "F.Cu" "F.Mask" "F.Paste")
			(net "P0V975")
		)
		(pad "2" smd rect
			(at 0 1.397)
			(size 1.651 1.27)
			(layers "F.Cu" "F.Mask" "F.Paste")
			(net "GND")
		)
	)
	(footprint ""
		(layer "F.Cu")
		(at 217.043 -75.311 -45)
		(property "Reference" "VIA42"
			(at 0 0 315)
			(layer "F.SilkS")
			(hide yes)
			(effects
				(font
					(size 1.27 1.27)
				)
			)
		)
		(property "Value" "100OHM-8L-1D6MM-L18L16-GP"
			(at -3.721059 -4.508373 315)
			(unlocked yes)
			(layer "F.Fab")
			(hide yes)
			(effects
				(font
					(size 1.016 1.016)
					(thickness 0.1524)
				)
			)
		)
		(property "Device Type" "VIA-PCIE-4P-394076"
			(at -3.721059 -6.032502 315)
			(unlocked yes)
			(layer "F.Fab")
			(hide yes)
			(effects
				(font
					(size 1.016 1.016)
					(thickness 0.1524)
				)
			)
		)
		(duplicate_pad_numbers_are_jumpers no)
		(fp_poly
			(pts
				(xy -1.968472 -0.380877) (xy 1.968528 -0.380878) (xy 1.968527 0.381122) (xy -1.968472 0.381122)
			)
			(stroke
				(width 0)
				(type default)
			)
			(fill no)
			(layer "F.CrtYd")
		)
		(fp_poly
			(pts
				(xy -1.968472 -0.380877) (xy 1.968528 -0.380878) (xy 1.968527 0.381122) (xy -1.968472 0.381122)
			)
			(stroke
				(width 0)
				(type default)
			)
			(fill no)
			(layer "F.Fab")
		)
		(pad "1" thru_hole circle
			(at -1.5875 0 315)
			(size 0.508 0.508)
			(drill 0.254)
			(layers "*.Cu" "*.Mask")
			(remove_unused_layers no)
			(net "GND")
			(clearance 0.127)
			(thermal_gap 0.127)
		)
		(pad "2" thru_hole circle
			(at -0.571501 0 315)
			(size 0.508 0.508)
			(drill 0.254)
			(layers "*.Cu" "*.Mask")
			(remove_unused_layers no)
			(net "PHY_IOC_TO_CON_A_1_DP")
			(clearance 0.127)
			(thermal_gap 0.127)
		)
		(pad "3" thru_hole circle
			(at 0.571501 0 315)
			(size 0.508 0.508)
			(drill 0.254)
			(layers "*.Cu" "*.Mask")
			(remove_unused_layers no)
			(net "PHY_IOC_TO_CON_A_1_DN")
			(clearance 0.127)
			(thermal_gap 0.127)
		)
		(pad "4" thru_hole circle
			(at 1.5875 0 315)
			(size 0.508 0.508)
			(drill 0.254)
			(layers "*.Cu" "*.Mask")
			(remove_unused_layers no)
			(net "GND")
			(clearance 0.127)
			(thermal_gap 0.127)
		)
	)
	(footprint ""
		(layer "F.Cu")
		(at 58.486548 -131.31292 180)
		(property "Reference" "R288"
			(at 0 0 180)
			(layer "F.SilkS")
			(hide yes)
			(effects
				(font
					(size 1.27 1.27)
				)
			)
		)
		(property "Value" "0R2J-2-GP"
			(at 0.064008 -3.993896 180)
			(unlocked yes)
			(layer "F.Fab")
			(hide yes)
			(effects
				(font
					(size 1.016 1.016)
					(thickness 0.1524)
				)
			)
		)
		(property "Device Type" "R402H16"
			(at 0.064008 -5.517896 180)
			(unlocked yes)
			(layer "F.Fab")
			(hide yes)
			(effects
				(font
					(size 1.016 1.016)
					(thickness 0.1524)
				)
			)
		)
		(duplicate_pad_numbers_are_jumpers no)
		(fp_line
			(start 0.508 -0.9398)
			(end -0.508 -0.9398)
			(stroke
				(width 0.1524)
				(type default)
			)
			(layer "F.SilkS")
		)
		(fp_line
			(start -0.508 -0.9398)
			(end -0.508 0.9398)
			(stroke
				(width 0.1524)
				(type default)
			)
			(layer "F.SilkS")
		)
		(fp_rect
			(start -0.508 0.9398)
			(end 0.508 -0.9398)
			(stroke
				(width 0)
				(type default)
			)
			(fill no)
			(layer "F.CrtYd")
		)
		(fp_rect
			(start -0.508 0.9398)
			(end 0.508 -0.9398)
			(stroke
				(width 0)
				(type default)
			)
			(fill no)
			(layer "F.Fab")
		)
		(pad "1" smd custom
			(at 0 -0.4445 180)
			(size 0.1397 0.1397)
			(layers "F.Cu" "F.Mask" "F.Paste")
			(net "EXP_SPARE_0")
			(options
				(clearance outline)
				(anchor circle)
			)
			(primitives
				(gr_poly
					(pts
						(arc
							(start -0.1778 -0.2794)
							(mid -0.249642 -0.249642)
							(end -0.2794 -0.1778)
						)
						(arc
							(start -0.2794 0.1778)
							(mid -0.249642 0.249642)
							(end -0.1778 0.2794)
						)
						(arc
							(start 0.1778 0.2794)
							(mid 0.249642 0.249642)
							(end 0.2794 0.1778)
						)
						(arc
							(start 0.2794 -0.1778)
							(mid 0.249642 -0.249642)
							(end 0.1778 -0.2794)
						)
					)
					(width 0)
					(fill yes)
				)
			)
		)
		(pad "2" smd custom
			(at 0 0.4445 180)
			(size 0.1397 0.1397)
			(layers "F.Cu" "F.Mask" "F.Paste")
			(net "EXP_SPARE_0_R")
			(options
				(clearance outline)
				(anchor circle)
			)
			(primitives
				(gr_poly
					(pts
						(arc
							(start -0.1778 -0.2794)
							(mid -0.249642 -0.249642)
							(end -0.2794 -0.1778)
						)
						(arc
							(start -0.2794 0.1778)
							(mid -0.249642 0.249642)
							(end -0.1778 0.2794)
						)
						(arc
							(start 0.1778 0.2794)
							(mid 0.249642 0.249642)
							(end 0.2794 0.1778)
						)
						(arc
							(start 0.2794 -0.1778)
							(mid 0.249642 -0.249642)
							(end 0.1778 -0.2794)
						)
					)
					(width 0)
					(fill yes)
				)
			)
		)
	)
	(footprint ""
		(layer "F.Cu")
		(at 162.85464 -139.583922 90)
		(property "Reference" "R516"
			(at 0 0 90)
			(layer "F.SilkS")
			(hide yes)
			(effects
				(font
					(size 1.27 1.27)
				)
			)
		)
		(property "Value" "0R2J-2-GP"
			(at 0.064008 -3.993896 90)
			(unlocked yes)
			(layer "F.Fab")
			(hide yes)
			(effects
				(font
					(size 1.016 1.016)
					(thickness 0.1524)
				)
			)
		)
		(property "Device Type" "R402H16"
			(at 0.064008 -5.517896 90)
			(unlocked yes)
			(layer "F.Fab")
			(hide yes)
			(effects
				(font
					(size 1.016 1.016)
					(thickness 0.1524)
				)
			)
		)
		(duplicate_pad_numbers_are_jumpers no)
		(fp_line
			(start 0.508 -0.9398)
			(end -0.508 -0.9398)
			(stroke
				(width 0.1524)
				(type default)
			)
			(layer "F.SilkS")
		)
		(fp_line
			(start -0.508 -0.9398)
			(end -0.508 0.9398)
			(stroke
				(width 0.1524)
				(type default)
			)
			(layer "F.SilkS")
		)
		(fp_rect
			(start -0.508 0.9398)
			(end 0.508 -0.9398)
			(stroke
				(width 0)
				(type default)
			)
			(fill no)
			(layer "F.CrtYd")
		)
		(fp_rect
			(start -0.508 0.9398)
			(end 0.508 -0.9398)
			(stroke
				(width 0)
				(type default)
			)
			(fill no)
			(layer "F.Fab")
		)
		(pad "1" smd custom
			(at 0 -0.4445 90)
			(size 0.1397 0.1397)
			(layers "F.Cu" "F.Mask" "F.Paste")
			(net "P1V8_STBY_VO")
			(options
				(clearance outline)
				(anchor circle)
			)
			(primitives
				(gr_poly
					(pts
						(arc
							(start -0.1778 -0.2794)
							(mid -0.249642 -0.249642)
							(end -0.2794 -0.1778)
						)
						(arc
							(start -0.2794 0.1778)
							(mid -0.249642 0.249642)
							(end -0.1778 0.2794)
						)
						(arc
							(start 0.1778 0.2794)
							(mid 0.249642 0.249642)
							(end 0.2794 0.1778)
						)
						(arc
							(start 0.2794 -0.1778)
							(mid 0.249642 -0.249642)
							(end 0.1778 -0.2794)
						)
					)
					(width 0)
					(fill yes)
				)
			)
		)
		(pad "2" smd custom
			(at 0 0.4445 90)
			(size 0.1397 0.1397)
			(layers "F.Cu" "F.Mask" "F.Paste")
			(net "P1V8_STBY_CC_R")
			(options
				(clearance outline)
				(anchor circle)
			)
			(primitives
				(gr_poly
					(pts
						(arc
							(start -0.1778 -0.2794)
							(mid -0.249642 -0.249642)
							(end -0.2794 -0.1778)
						)
						(arc
							(start -0.2794 0.1778)
							(mid -0.249642 0.249642)
							(end -0.1778 0.2794)
						)
						(arc
							(start 0.1778 0.2794)
							(mid 0.249642 0.249642)
							(end 0.2794 0.1778)
						)
						(arc
							(start 0.2794 -0.1778)
							(mid 0.249642 -0.249642)
							(end 0.1778 -0.2794)
						)
					)
					(width 0)
					(fill yes)
				)
			)
		)
	)
	(footprint ""
		(layer "F.Cu")
		(at 162.8648 -140.6398 -90)
		(property "Reference" "R515"
			(at 0 0 270)
			(layer "F.SilkS")
			(hide yes)
			(effects
				(font
					(size 1.27 1.27)
				)
			)
		)
		(property "Value" "13K7R2F-GP"
			(at 0.064008 -3.993896 270)
			(unlocked yes)
			(layer "F.Fab")
			(hide yes)
			(effects
				(font
					(size 1.016 1.016)
					(thickness 0.1524)
				)
			)
		)
		(property "Device Type" "R402H16"
			(at 0.064008 -5.517896 270)
			(unlocked yes)
			(layer "F.Fab")
			(hide yes)
			(effects
				(font
					(size 1.016 1.016)
					(thickness 0.1524)
				)
			)
		)
		(duplicate_pad_numbers_are_jumpers no)
		(fp_line
			(start -0.508 -0.9398)
			(end -0.508 0.9398)
			(stroke
				(width 0.1524)
				(type default)
			)
			(layer "F.SilkS")
		)
		(fp_line
			(start 0.508 -0.9398)
			(end -0.508 -0.9398)
			(stroke
				(width 0.1524)
				(type default)
			)
			(layer "F.SilkS")
		)
		(fp_rect
			(start -0.508 0.9398)
			(end 0.508 -0.9398)
			(stroke
				(width 0)
				(type default)
			)
			(fill no)
			(layer "F.CrtYd")
		)
		(fp_rect
			(start -0.508 0.9398)
			(end 0.508 -0.9398)
			(stroke
				(width 0)
				(type default)
			)
			(fill no)
			(layer "F.Fab")
		)
		(pad "1" smd custom
			(at 0 -0.4445 270)
			(size 0.1397 0.1397)
			(layers "F.Cu" "F.Mask" "F.Paste")
			(net "P1V8_STBY_CC_R")
			(options
				(clearance outline)
				(anchor circle)
			)
			(primitives
				(gr_poly
					(pts
						(arc
							(start -0.1778 -0.2794)
							(mid -0.249642 -0.249642)
							(end -0.2794 -0.1778)
						)
						(arc
							(start -0.2794 0.1778)
							(mid -0.249642 0.249642)
							(end -0.1778 0.2794)
						)
						(arc
							(start 0.1778 0.2794)
							(mid 0.249642 0.249642)
							(end 0.2794 0.1778)
						)
						(arc
							(start 0.2794 -0.1778)
							(mid 0.249642 -0.249642)
							(end 0.1778 -0.2794)
						)
					)
					(width 0)
					(fill yes)
				)
			)
		)
		(pad "2" smd custom
			(at 0 0.4445 270)
			(size 0.1397 0.1397)
			(layers "F.Cu" "F.Mask" "F.Paste")
			(net "P1V8_STBY_VFB")
			(options
				(clearance outline)
				(anchor circle)
			)
			(primitives
				(gr_poly
					(pts
						(arc
							(start -0.1778 -0.2794)
							(mid -0.249642 -0.249642)
							(end -0.2794 -0.1778)
						)
						(arc
							(start -0.2794 0.1778)
							(mid -0.249642 0.249642)
							(end -0.1778 0.2794)
						)
						(arc
							(start 0.1778 0.2794)
							(mid 0.249642 0.249642)
							(end 0.2794 0.1778)
						)
						(arc
							(start 0.2794 -0.1778)
							(mid 0.249642 -0.249642)
							(end 0.1778 -0.2794)
						)
					)
					(width 0)
					(fill yes)
				)
			)
		)
	)
	(footprint ""
		(layer "F.Cu")
		(at 29.367226 -180.33873 180)
		(property "Reference" "C182"
			(at 0 0 180)
			(layer "F.SilkS")
			(hide yes)
			(effects
				(font
					(size 1.27 1.27)
				)
			)
		)
		(property "Value" "SC1U16V3KX-5GP"
			(at 0 -2.8194 180)
			(unlocked yes)
			(layer "F.Fab")
			(hide yes)
			(effects
				(font
					(size 1.016 1.016)
					(thickness 0.1524)
				)
			)
		)
		(property "Device Type" "C603H36"
			(at 0 -4.3434 180)
			(unlocked yes)
			(layer "F.Fab")
			(hide yes)
			(effects
				(font
					(size 1.016 1.016)
					(thickness 0.1524)
				)
			)
		)
		(duplicate_pad_numbers_are_jumpers no)
		(fp_line
			(start 0.508 0)
			(end -0.508 0)
			(stroke
				(width 0.2032)
				(type default)
			)
			(layer "F.SilkS")
		)
		(fp_rect
			(start -0.5842 1.3335)
			(end 0.5842 -1.3335)
			(stroke
				(width 0)
				(type default)
			)
			(fill no)
			(layer "F.CrtYd")
		)
		(fp_rect
			(start -0.5842 1.3335)
			(end 0.5842 -1.3335)
			(stroke
				(width 0)
				(type default)
			)
			(fill no)
			(layer "F.Fab")
		)
		(pad "1" smd custom
			(at 0 -0.762 180)
			(size 0.2159 0.2159)
			(layers "F.Cu" "F.Mask" "F.Paste")
			(net "GND")
			(options
				(clearance outline)
				(anchor circle)
			)
			(primitives
				(gr_poly
					(pts
						(arc
							(start -0.3302 -0.4318)
							(mid -0.402042 -0.402042)
							(end -0.4318 -0.3302)
						)
						(arc
							(start -0.4318 0.3302)
							(mid -0.402042 0.402042)
							(end -0.3302 0.4318)
						)
						(arc
							(start 0.3302 0.4318)
							(mid 0.402042 0.402042)
							(end 0.4318 0.3302)
						)
						(arc
							(start 0.4318 -0.3302)
							(mid 0.402042 -0.402042)
							(end 0.3302 -0.4318)
						)
					)
					(width 0)
					(fill yes)
				)
			)
		)
		(pad "2" smd custom
			(at 0 0.762 180)
			(size 0.2159 0.2159)
			(layers "F.Cu" "F.Mask" "F.Paste")
			(net "P3V3_STBY_VREG")
			(options
				(clearance outline)
				(anchor circle)
			)
			(primitives
				(gr_poly
					(pts
						(arc
							(start -0.3302 -0.4318)
							(mid -0.402042 -0.402042)
							(end -0.4318 -0.3302)
						)
						(arc
							(start -0.4318 0.3302)
							(mid -0.402042 0.402042)
							(end -0.3302 0.4318)
						)
						(arc
							(start 0.3302 0.4318)
							(mid 0.402042 0.402042)
							(end 0.4318 0.3302)
						)
						(arc
							(start 0.4318 -0.3302)
							(mid 0.402042 -0.402042)
							(end 0.3302 -0.4318)
						)
					)
					(width 0)
					(fill yes)
				)
			)
		)
	)
	(footprint ""
		(layer "F.Cu")
		(at 86.854538 -57.655968 -90)
		(property "Reference" "R3"
			(at 0 0 270)
			(layer "F.SilkS")
			(hide yes)
			(effects
				(font
					(size 1.27 1.27)
				)
			)
		)
		(property "Value" "4K7R2F-GP"
			(at 0.064008 -3.993896 270)
			(unlocked yes)
			(layer "F.Fab")
			(hide yes)
			(effects
				(font
					(size 1.016 1.016)
					(thickness 0.1524)
				)
			)
		)
		(property "Device Type" "R402H16"
			(at 0.064008 -5.517896 270)
			(unlocked yes)
			(layer "F.Fab")
			(hide yes)
			(effects
				(font
					(size 1.016 1.016)
					(thickness 0.1524)
				)
			)
		)
		(duplicate_pad_numbers_are_jumpers no)
		(fp_line
			(start -0.508 -0.9398)
			(end -0.508 0.9398)
			(stroke
				(width 0.1524)
				(type default)
			)
			(layer "F.SilkS")
		)
		(fp_line
			(start 0.508 -0.9398)
			(end -0.508 -0.9398)
			(stroke
				(width 0.1524)
				(type default)
			)
			(layer "F.SilkS")
		)
		(fp_rect
			(start -0.508 0.9398)
			(end 0.508 -0.9398)
			(stroke
				(width 0)
				(type default)
			)
			(fill no)
			(layer "F.CrtYd")
		)
		(fp_rect
			(start -0.508 0.9398)
			(end 0.508 -0.9398)
			(stroke
				(width 0)
				(type default)
			)
			(fill no)
			(layer "F.Fab")
		)
		(pad "1" smd custom
			(at 0 -0.4445 270)
			(size 0.1397 0.1397)
			(layers "F.Cu" "F.Mask" "F.Paste")
			(net "I2C_MEZZ_ALERT_N")
			(options
				(clearance outline)
				(anchor circle)
			)
			(primitives
				(gr_poly
					(pts
						(arc
							(start -0.1778 -0.2794)
							(mid -0.249642 -0.249642)
							(end -0.2794 -0.1778)
						)
						(arc
							(start -0.2794 0.1778)
							(mid -0.249642 0.249642)
							(end -0.1778 0.2794)
						)
						(arc
							(start 0.1778 0.2794)
							(mid 0.249642 0.249642)
							(end 0.2794 0.1778)
						)
						(arc
							(start 0.2794 -0.1778)
							(mid 0.249642 -0.249642)
							(end 0.1778 -0.2794)
						)
					)
					(width 0)
					(fill yes)
				)
			)
		)
		(pad "2" smd custom
			(at 0 0.4445 270)
			(size 0.1397 0.1397)
			(layers "F.Cu" "F.Mask" "F.Paste")
			(net "P3V3_STBY")
			(options
				(clearance outline)
				(anchor circle)
			)
			(primitives
				(gr_poly
					(pts
						(arc
							(start -0.1778 -0.2794)
							(mid -0.249642 -0.249642)
							(end -0.2794 -0.1778)
						)
						(arc
							(start -0.2794 0.1778)
							(mid -0.249642 0.249642)
							(end -0.1778 0.2794)
						)
						(arc
							(start 0.1778 0.2794)
							(mid 0.249642 0.249642)
							(end 0.2794 0.1778)
						)
						(arc
							(start 0.2794 -0.1778)
							(mid 0.249642 -0.249642)
							(end 0.1778 -0.2794)
						)
					)
					(width 0)
					(fill yes)
				)
			)
		)
	)
)
